(kicad_pcb
	(version 20241229)
	(generator "pcbnew")
	(generator_version "9.0")
	(general
		(thickness 1.61)
		(legacy_teardrops no)
	)
	(paper "A3")
	(title_block
		(title "RDIMM DDR5 Tester")
		(date "2026-05-21")
		(rev "2.2.0")
		(company "Antmicro")
		(comment 9 "footprints 424-429 of 796")
	)
	(layers
		(0 "F.Cu" signal)
		(4 "In1.Cu" power)
		(6 "In2.Cu" mixed)
		(8 "In3.Cu" power)
		(10 "In4.Cu" mixed)
		(12 "In5.Cu" power)
		(14 "In6.Cu" mixed)
		(16 "In7.Cu" power)
		(18 "In8.Cu" power)
		(20 "In9.Cu" mixed)
		(22 "In10.Cu" power)
		(2 "B.Cu" signal)
		(9 "F.Adhes" user "F.Adhesive")
		(11 "B.Adhes" user "B.Adhesive")
		(13 "F.Paste" user)
		(15 "B.Paste" user)
		(5 "F.SilkS" user "F.Silkscreen")
		(7 "B.SilkS" user "B.Silkscreen")
		(1 "F.Mask" user)
		(3 "B.Mask" user)
		(17 "Dwgs.User" user "User.Drawings")
		(19 "Cmts.User" user "User.Comments")
		(21 "Eco1.User" user "User.Eco1")
		(23 "Eco2.User" user "User.Eco2")
		(25 "Edge.Cuts" user)
		(27 "Margin" user)
		(31 "F.CrtYd" user "F.Courtyard")
		(29 "B.CrtYd" user "B.Courtyard")
		(35 "F.Fab" user)
		(33 "B.Fab" user)
	)
	(footprint "antmicro-footprints:TP_SMD_1mm"
		(layer "B.Cu")
		(at 139.924499 166.499 -90)
		(property "Reference" "TP1"
			(at -0.95 0.8 90)
			(layer "B.SilkS")
			(effects
				(font
					(size 0.7 0.7)
					(thickness 0.15)
				)
				(justify left bottom mirror)
			)
		)
		(property "Value" "TP_1mm_SMD"
			(at 0 -1.4 90)
			(layer "B.Fab")
			(effects
				(font
					(size 0.7 0.7)
					(thickness 0.15)
				)
				(justify left bottom mirror)
			)
		)
		(property "MPN" ""
			(at 0 0 270)
			(unlocked yes)
			(layer "B.Fab")
			(hide yes)
			(effects
				(font
					(size 1 1)
					(thickness 0.15)
				)
				(justify mirror)
			)
		)
		(property "Manufacturer" ""
			(at 0 0 270)
			(unlocked yes)
			(layer "B.Fab")
			(hide yes)
			(effects
				(font
					(size 1 1)
					(thickness 0.15)
				)
				(justify mirror)
			)
		)
		(property "Author" "Antmicro"
			(at 0 0 270)
			(unlocked yes)
			(layer "B.Fab")
			(hide yes)
			(effects
				(font
					(size 1 1)
					(thickness 0.15)
				)
				(justify mirror)
			)
		)
		(property "License" "Apache-2.0"
			(at 0 0 270)
			(unlocked yes)
			(layer "B.Fab")
			(hide yes)
			(effects
				(font
					(size 1 1)
					(thickness 0.15)
				)
				(justify mirror)
			)
		)
		(sheetname "/Debug FTDI + VNA/")
		(sheetfile "debug-ftdi.kicad_sch")
		(attr exclude_from_pos_files)
		(fp_circle
			(center 0 0)
			(end 0.6 0)
			(stroke
				(width 0.05)
				(type default)
			)
			(fill no)
			(layer "B.CrtYd")
		)
		(fp_text user "Author: Antmicro"
			(at -0.5 -4 90)
			(layer "B.Fab")
			(effects
				(font
					(size 0.7 0.7)
					(thickness 0.15)
				)
				(justify left bottom mirror)
			)
		)
		(fp_text user "${REFERENCE}"
			(at -0.5 -2.8 90)
			(layer "B.Fab")
			(effects
				(font
					(size 0.7 0.7)
					(thickness 0.15)
				)
				(justify left bottom mirror)
			)
		)
		(fp_text user "License: Apache-2.0"
			(at -0.5 -5.2 90)
			(layer "B.Fab")
			(effects
				(font
					(size 0.7 0.7)
					(thickness 0.15)
				)
				(justify left bottom mirror)
			)
		)
		(pad "1" smd circle
			(at 0 0 270)
			(size 1 1)
			(layers "B.Cu" "B.Mask")
			(net 776 "/Debug FTDI + VNA/FTDI_JTAG_RST")
			(pinfunction "1")
			(pintype "passive")
		)
	)
	(footprint "antmicro-footprints:R_0402_1005Metric"
		(layer "B.Cu")
		(at 139.6 152.4 -90)
		(descr "Resistor SMD 0402")
		(tags "resistor SMD 0402")
		(property "Reference" "R114"
			(at 8 -0.375 90)
			(layer "B.SilkS")
			(effects
				(font
					(size 0.7 0.7)
					(thickness 0.15)
				)
				(justify left bottom mirror)
			)
		)
		(property "Value" "R_2k2_0402"
			(at -1.011843 -1.772047 90)
			(layer "B.Fab")
			(effects
				(font
					(size 0.7 0.7)
					(thickness 0.15)
				)
				(justify left bottom mirror)
			)
		)
		(property "Datasheet" "https://www.bourns.com/docs/product-datasheets/cr.pdf"
			(at 0 0 270)
			(layer "F.Fab")
			(hide yes)
			(effects
				(font
					(size 1.27 1.27)
					(thickness 0.15)
				)
			)
		)
		(property "Manufacturer" "Bourns"
			(at 0 0 270)
			(unlocked yes)
			(layer "B.Fab")
			(hide yes)
			(effects
				(font
					(size 1 1)
					(thickness 0.15)
				)
				(justify mirror)
			)
		)
		(property "MPN" "CR0402-FX-2201GLF"
			(at 0 0 270)
			(unlocked yes)
			(layer "B.Fab")
			(hide yes)
			(effects
				(font
					(size 1 1)
					(thickness 0.15)
				)
				(justify mirror)
			)
		)
		(property "Val" "2k2"
			(at 0 0 270)
			(unlocked yes)
			(layer "B.Fab")
			(hide yes)
			(effects
				(font
					(size 1 1)
					(thickness 0.15)
				)
				(justify mirror)
			)
		)
		(property "License" "Apache-2.0"
			(at 0 0 270)
			(unlocked yes)
			(layer "B.Fab")
			(hide yes)
			(effects
				(font
					(size 1 1)
					(thickness 0.15)
				)
				(justify mirror)
			)
		)
		(property "Author" "Antmicro"
			(at 0 0 270)
			(unlocked yes)
			(layer "B.Fab")
			(hide yes)
			(effects
				(font
					(size 1 1)
					(thickness 0.15)
				)
				(justify mirror)
			)
		)
		(property "Tolerance" "1%"
			(at 0 0 270)
			(unlocked yes)
			(layer "B.Fab")
			(hide yes)
			(effects
				(font
					(size 1 1)
					(thickness 0.15)
				)
				(justify mirror)
			)
		)
		(sheetname "/Ethernet/")
		(sheetfile "ethernet.kicad_sch")
		(attr smd)
		(fp_rect
			(start -0.925 0.47)
			(end 0.925 -0.47)
			(stroke
				(width 0.05)
				(type default)
			)
			(fill no)
			(layer "B.CrtYd")
		)
		(fp_rect
			(start -0.5 0.25)
			(end 0.5 -0.25)
			(stroke
				(width 0.15)
				(type solid)
			)
			(fill no)
			(layer "B.Fab")
		)
		(fp_text user "Author: Antmicro"
			(at -0.95 -4.169 90)
			(layer "B.Fab")
			(effects
				(font
					(size 0.7 0.7)
					(thickness 0.15)
				)
				(justify left bottom mirror)
			)
		)
		(fp_text user "License: Apache-2.0"
			(at -0.95 -5.169 90)
			(layer "B.Fab")
			(effects
				(font
					(size 0.7 0.7)
					(thickness 0.15)
				)
				(justify left bottom mirror)
			)
		)
		(fp_text user "${REFERENCE}"
			(at -0.95 -3.168 90)
			(layer "B.Fab")
			(effects
				(font
					(size 0.7 0.7)
					(thickness 0.15)
				)
				(justify left bottom mirror)
			)
		)
		(pad "1" smd roundrect
			(at -0.48 0 270)
			(size 0.59 0.64)
			(layers "B.Cu" "B.Mask" "B.Paste")
			(roundrect_rratio 0.25)
			(net 394 "/Ethernet/ETH.RXD1")
			(pintype "passive")
		)
		(pad "2" smd roundrect
			(at 0.48 0 270)
			(size 0.59 0.64)
			(layers "B.Cu" "B.Mask" "B.Paste")
			(roundrect_rratio 0.25)
			(net 1 "GND")
			(pintype "passive")
		)
	)
	(footprint "antmicro-footprints:R_0402_1005Metric"
		(layer "B.Cu")
		(at 138.55 150.025 90)
		(descr "Resistor SMD 0402")
		(tags "resistor SMD 0402")
		(property "Reference" "R103"
			(at -10.375 0.409 90)
			(layer "B.SilkS")
			(effects
				(font
					(size 0.7 0.7)
					(thickness 0.15)
				)
				(justify right bottom mirror)
			)
		)
		(property "Value" "R_10k_0402"
			(at -1.011843 -1.772047 90)
			(layer "B.Fab")
			(effects
				(font
					(size 0.7 0.7)
					(thickness 0.15)
				)
				(justify right bottom mirror)
			)
		)
		(property "Datasheet" "https://www.bourns.com/docs/product-datasheets/cr.pdf"
			(at 0 0 90)
			(layer "F.Fab")
			(hide yes)
			(effects
				(font
					(size 1.27 1.27)
					(thickness 0.15)
				)
			)
		)
		(property "Manufacturer" "Bourns"
			(at 0 0 90)
			(unlocked yes)
			(layer "B.Fab")
			(hide yes)
			(effects
				(font
					(size 1 1)
					(thickness 0.15)
				)
				(justify mirror)
			)
		)
		(property "MPN" "CR0402-FX-1002GLF"
			(at 0 0 90)
			(unlocked yes)
			(layer "B.Fab")
			(hide yes)
			(effects
				(font
					(size 1 1)
					(thickness 0.15)
				)
				(justify mirror)
			)
		)
		(property "Val" "10k"
			(at 0 0 90)
			(unlocked yes)
			(layer "B.Fab")
			(hide yes)
			(effects
				(font
					(size 1 1)
					(thickness 0.15)
				)
				(justify mirror)
			)
		)
		(property "License" "Apache-2.0"
			(at 0 0 90)
			(unlocked yes)
			(layer "B.Fab")
			(hide yes)
			(effects
				(font
					(size 1 1)
					(thickness 0.15)
				)
				(justify mirror)
			)
		)
		(property "Author" "Antmicro"
			(at 0 0 90)
			(unlocked yes)
			(layer "B.Fab")
			(hide yes)
			(effects
				(font
					(size 1 1)
					(thickness 0.15)
				)
				(justify mirror)
			)
		)
		(property "Tolerance" "1%"
			(at 0 0 90)
			(unlocked yes)
			(layer "B.Fab")
			(hide yes)
			(effects
				(font
					(size 1 1)
					(thickness 0.15)
				)
				(justify mirror)
			)
		)
		(sheetname "/Ethernet/")
		(sheetfile "ethernet.kicad_sch")
		(attr smd)
		(fp_rect
			(start -0.925 0.47)
			(end 0.925 -0.47)
			(stroke
				(width 0.05)
				(type default)
			)
			(fill no)
			(layer "B.CrtYd")
		)
		(fp_rect
			(start -0.5 0.25)
			(end 0.5 -0.25)
			(stroke
				(width 0.15)
				(type solid)
			)
			(fill no)
			(layer "B.Fab")
		)
		(fp_text user "Author: Antmicro"
			(at -0.95 -4.169 270)
			(layer "B.Fab")
			(effects
				(font
					(size 0.7 0.7)
					(thickness 0.15)
				)
				(justify left bottom mirror)
			)
		)
		(fp_text user "${REFERENCE}"
			(at -0.95 -3.168 270)
			(layer "B.Fab")
			(effects
				(font
					(size 0.7 0.7)
					(thickness 0.15)
				)
				(justify left bottom mirror)
			)
		)
		(fp_text user "License: Apache-2.0"
			(at -0.95 -5.169 270)
			(layer "B.Fab")
			(effects
				(font
					(size 0.7 0.7)
					(thickness 0.15)
				)
				(justify left bottom mirror)
			)
		)
		(pad "1" smd roundrect
			(at -0.48 0 90)
			(size 0.59 0.64)
			(layers "B.Cu" "B.Mask" "B.Paste")
			(roundrect_rratio 0.25)
			(net 395 "/Ethernet/ETH.RXD2")
			(pintype "passive")
		)
		(pad "2" smd roundrect
			(at 0.48 0 90)
			(size 0.59 0.64)
			(layers "B.Cu" "B.Mask" "B.Paste")
			(roundrect_rratio 0.25)
			(net 797 "+1V8")
			(pintype "passive")
		)
	)
	(footprint "antmicro-footprints:C_0603_1608Metric"
		(layer "B.Cu")
		(at 174.6 159.5 90)
		(descr "Capacitor SMD 0603")
		(tags "capacitor 0603")
		(property "Reference" "C14"
			(at -3.4 0.3 90)
			(layer "B.SilkS")
			(effects
				(font
					(size 0.7 0.7)
					(thickness 0.15)
				)
				(justify right bottom mirror)
			)
		)
		(property "Value" "C_47u_0603"
			(at -1.42757 -1.770288 90)
			(layer "B.Fab")
			(effects
				(font
					(size 0.7 0.7)
					(thickness 0.15)
				)
				(justify right bottom mirror)
			)
		)
		(property "Datasheet" "https://www.murata.com/products/productdetail?partno=GRM188R60J476ME15%23"
			(at 0 0 90)
			(layer "F.Fab")
			(hide yes)
			(effects
				(font
					(size 1.27 1.27)
					(thickness 0.15)
				)
			)
		)
		(property "Manufacturer" "Murata"
			(at 0 0 90)
			(unlocked yes)
			(layer "B.Fab")
			(hide yes)
			(effects
				(font
					(size 1 1)
					(thickness 0.15)
				)
				(justify mirror)
			)
		)
		(property "MPN" "GRM188R60J476ME15D"
			(at 0 0 90)
			(unlocked yes)
			(layer "B.Fab")
			(hide yes)
			(effects
				(font
					(size 1 1)
					(thickness 0.15)
				)
				(justify mirror)
			)
		)
		(property "Val" "47u"
			(at 0 0 90)
			(unlocked yes)
			(layer "B.Fab")
			(hide yes)
			(effects
				(font
					(size 1 1)
					(thickness 0.15)
				)
				(justify mirror)
			)
		)
		(property "License" "Apache-2.0"
			(at 0 0 90)
			(unlocked yes)
			(layer "B.Fab")
			(hide yes)
			(effects
				(font
					(size 1 1)
					(thickness 0.15)
				)
				(justify mirror)
			)
		)
		(property "Author" "Antmicro"
			(at 0 0 90)
			(unlocked yes)
			(layer "B.Fab")
			(hide yes)
			(effects
				(font
					(size 1 1)
					(thickness 0.15)
				)
				(justify mirror)
			)
		)
		(property "Voltage" ""
			(at 0 0 90)
			(unlocked yes)
			(layer "B.Fab")
			(hide yes)
			(effects
				(font
					(size 1 1)
					(thickness 0.15)
				)
				(justify mirror)
			)
		)
		(property "Dielectric" ""
			(at 0 0 90)
			(unlocked yes)
			(layer "B.Fab")
			(hide yes)
			(effects
				(font
					(size 1 1)
					(thickness 0.15)
				)
				(justify mirror)
			)
		)
		(sheetname "/FPGA power/")
		(sheetfile "fpga-power.kicad_sch")
		(attr smd)
		(fp_line
			(start -0.15 -0.4)
			(end 0.15 -0.4)
			(stroke
				(width 0.15)
				(type solid)
			)
			(layer "B.SilkS")
		)
		(fp_line
			(start -0.15 0.4)
			(end 0.15 0.4)
			(stroke
				(width 0.15)
				(type solid)
			)
			(layer "B.SilkS")
		)
		(fp_rect
			(start -1.25 0.65)
			(end 1.25 -0.65)
			(stroke
				(width 0.05)
				(type solid)
			)
			(fill no)
			(layer "B.CrtYd")
		)
		(fp_rect
			(start -0.8 0.4)
			(end 0.8 -0.4)
			(stroke
				(width 0.15)
				(type solid)
			)
			(fill no)
			(layer "B.Fab")
		)
		(fp_text user "${REFERENCE}"
			(at -1.682 -3.895 270)
			(layer "B.Fab")
			(effects
				(font
					(size 0.7 0.7)
					(thickness 0.15)
				)
				(justify left bottom mirror)
			)
		)
		(fp_text user "License: Apache-2.0"
			(at -1.682 -5.895 270)
			(layer "B.Fab")
			(effects
				(font
					(size 0.7 0.7)
					(thickness 0.15)
				)
				(justify left bottom mirror)
			)
		)
		(fp_text user "Author: Antmicro"
			(at -1.682 -4.894 270)
			(layer "B.Fab")
			(effects
				(font
					(size 0.7 0.7)
					(thickness 0.15)
				)
				(justify left bottom mirror)
			)
		)
		(pad "1" smd roundrect
			(at -0.7 0 90)
			(size 0.8 1)
			(layers "B.Cu" "B.Mask" "B.Paste")
			(roundrect_rratio 0.2)
			(net 172 "+1V2_MGTAVTT")
			(pintype "passive")
		)
		(pad "2" smd roundrect
			(at 0.7 0 90)
			(size 0.8 1)
			(layers "B.Cu" "B.Mask" "B.Paste")
			(roundrect_rratio 0.2)
			(net 1 "GND")
			(pintype "passive")
		)
	)
	(footprint "antmicro-footprints:C_0402_1005Metric"
		(layer "B.Cu")
		(at 166.1 150.44)
		(descr "Capacitor SMD 0402")
		(tags "capacitor SMD 0402")
		(property "Reference" "C3"
			(at -2.4 0.46 0)
			(layer "B.SilkS")
			(effects
				(font
					(size 0.7 0.7)
					(thickness 0.15)
				)
				(justify right bottom mirror)
			)
		)
		(property "Value" "C_100n_0402"
			(at -1.022927 -2.155213 0)
			(layer "B.Fab")
			(effects
				(font
					(size 0.7 0.7)
					(thickness 0.15)
				)
				(justify right bottom mirror)
			)
		)
		(property "Datasheet" "https://www.murata.com/products/productdetail?partno=GRM155R61H104KE14%23"
			(at 0 0 0)
			(layer "F.Fab")
			(hide yes)
			(effects
				(font
					(size 1.27 1.27)
					(thickness 0.15)
				)
			)
		)
		(property "Manufacturer" "Murata"
			(at 0 0 0)
			(unlocked yes)
			(layer "B.Fab")
			(hide yes)
			(effects
				(font
					(size 1 1)
					(thickness 0.15)
				)
				(justify mirror)
			)
		)
		(property "MPN" "GRM155R61H104KE14D"
			(at 0 0 0)
			(unlocked yes)
			(layer "B.Fab")
			(hide yes)
			(effects
				(font
					(size 1 1)
					(thickness 0.15)
				)
				(justify mirror)
			)
		)
		(property "Val" "100n"
			(at 0 0 0)
			(unlocked yes)
			(layer "B.Fab")
			(hide yes)
			(effects
				(font
					(size 1 1)
					(thickness 0.15)
				)
				(justify mirror)
			)
		)
		(property "License" "Apache-2.0"
			(at 0 0 0)
			(unlocked yes)
			(layer "B.Fab")
			(hide yes)
			(effects
				(font
					(size 1 1)
					(thickness 0.15)
				)
				(justify mirror)
			)
		)
		(property "Author" "Antmicro"
			(at 0 0 0)
			(unlocked yes)
			(layer "B.Fab")
			(hide yes)
			(effects
				(font
					(size 1 1)
					(thickness 0.15)
				)
				(justify mirror)
			)
		)
		(property "Voltage" "50V"
			(at 0 0 0)
			(unlocked yes)
			(layer "B.Fab")
			(hide yes)
			(effects
				(font
					(size 1 1)
					(thickness 0.15)
				)
				(justify mirror)
			)
		)
		(property "Dielectric" "X5R"
			(at 0 0 0)
			(unlocked yes)
			(layer "B.Fab")
			(hide yes)
			(effects
				(font
					(size 1 1)
					(thickness 0.15)
				)
				(justify mirror)
			)
		)
		(sheetname "/HyperRAM + QSPI Flash/")
		(sheetfile "hyperram-flash.kicad_sch")
		(attr smd)
		(fp_rect
			(start -0.925 0.47)
			(end 0.925 -0.47)
			(stroke
				(width 0.05)
				(type default)
			)
			(fill no)
			(layer "B.CrtYd")
		)
		(fp_line
			(start -0.494 -0.248)
			(end -0.494 0.25)
			(stroke
				(width 0.15)
				(type solid)
			)
			(layer "B.Fab")
		)
		(fp_line
			(start -0.494 0.25)
			(end 0.504 0.25)
			(stroke
				(width 0.15)
				(type solid)
			)
			(layer "B.Fab")
		)
		(fp_line
			(start 0.504 -0.248)
			(end -0.494 -0.248)
			(stroke
				(width 0.15)
				(type solid)
			)
			(layer "B.Fab")
		)
		(fp_line
			(start 0.504 0.25)
			(end 0.504 -0.248)
			(stroke
				(width 0.15)
				(type solid)
			)
			(layer "B.Fab")
		)
		(fp_text user "License: Apache-2.0"
			(at -0.939 -5.799 180)
			(layer "B.Fab")
			(effects
				(font
					(size 0.7 0.7)
					(thickness 0.15)
				)
				(justify left bottom mirror)
			)
		)
		(fp_text user "${REFERENCE}"
			(at -0.939 -4.599 180)
			(layer "B.Fab")
			(effects
				(font
					(size 0.7 0.7)
					(thickness 0.15)
				)
				(justify left bottom mirror)
			)
		)
		(fp_text user "Author: Antmicro"
			(at -0.939 -3.399 180)
			(layer "B.Fab")
			(effects
				(font
					(size 0.7 0.7)
					(thickness 0.15)
				)
				(justify left bottom mirror)
			)
		)
		(pad "1" smd roundrect
			(at -0.48 0)
			(size 0.59 0.64)
			(layers "B.Cu" "B.Mask" "B.Paste")
			(roundrect_rratio 0.25)
			(net 797 "+1V8")
			(pintype "passive")
		)
		(pad "2" smd roundrect
			(at 0.48 0)
			(size 0.59 0.64)
			(layers "B.Cu" "B.Mask" "B.Paste")
			(roundrect_rratio 0.25)
			(net 1 "GND")
			(pintype "passive")
		)
	)
	(footprint "antmicro-footprints:R_0402_1005Metric"
		(layer "B.Cu")
		(at 252.2 185.349)
		(descr "Resistor SMD 0402")
		(tags "resistor SMD 0402")
		(property "Reference" "R243"
			(at 1 0.491 0)
			(layer "B.SilkS")
			(effects
				(font
					(size 0.7 0.7)
					(thickness 0.15)
				)
				(justify right bottom mirror)
			)
		)
		(property "Value" "R_4k7_0402"
			(at -1.011843 -1.772047 0)
			(layer "B.Fab")
			(effects
				(font
					(size 0.7 0.7)
					(thickness 0.15)
				)
				(justify right bottom mirror)
			)
		)
		(property "Datasheet" "https://www.bourns.com/docs/product-datasheets/cr.pdf"
			(at 0 0 0)
			(layer "F.Fab")
			(hide yes)
			(effects
				(font
					(size 1.27 1.27)
					(thickness 0.15)
				)
			)
		)
		(property "MPN" "CR0402-FX-4701GLF"
			(at 0 0 0)
			(unlocked yes)
			(layer "B.Fab")
			(hide yes)
			(effects
				(font
					(size 1 1)
					(thickness 0.15)
				)
				(justify mirror)
			)
		)
		(property "Manufacturer" "Bourns"
			(at 0 0 0)
			(unlocked yes)
			(layer "B.Fab")
			(hide yes)
			(effects
				(font
					(size 1 1)
					(thickness 0.15)
				)
				(justify mirror)
			)
		)
		(property "License" "Apache-2.0"
			(at 0 0 0)
			(unlocked yes)
			(layer "B.Fab")
			(hide yes)
			(effects
				(font
					(size 1 1)
					(thickness 0.15)
				)
				(justify mirror)
			)
		)
		(property "Author" "Antmicro"
			(at 0 0 0)
			(unlocked yes)
			(layer "B.Fab")
			(hide yes)
			(effects
				(font
					(size 1 1)
					(thickness 0.15)
				)
				(justify mirror)
			)
		)
		(property "Val" "4k7"
			(at 0 0 0)
			(unlocked yes)
			(layer "B.Fab")
			(hide yes)
			(effects
				(font
					(size 1 1)
					(thickness 0.15)
				)
				(justify mirror)
			)
		)
		(property "Tolerance" "1%"
			(at 0 0 0)
			(unlocked yes)
			(layer "B.Fab")
			(hide yes)
			(effects
				(font
					(size 1 1)
					(thickness 0.15)
				)
				(justify mirror)
			)
		)
		(sheetname "/I^{2}C + I3C/")
		(sheetfile "i2c.kicad_sch")
		(attr smd)
		(fp_rect
			(start -0.925 0.47)
			(end 0.925 -0.47)
			(stroke
				(width 0.05)
				(type default)
			)
			(fill no)
			(layer "B.CrtYd")
		)
		(fp_rect
			(start -0.5 0.25)
			(end 0.5 -0.25)
			(stroke
				(width 0.15)
				(type solid)
			)
			(fill no)
			(layer "B.Fab")
		)
		(fp_text user "License: Apache-2.0"
			(at -0.95 -5.169 180)
			(layer "B.Fab")
			(effects
				(font
					(size 0.7 0.7)
					(thickness 0.15)
				)
				(justify left bottom mirror)
			)
		)
		(fp_text user "${REFERENCE}"
			(at -0.95 -3.168 180)
			(layer "B.Fab")
			(effects
				(font
					(size 0.7 0.7)
					(thickness 0.15)
				)
				(justify left bottom mirror)
			)
		)
		(fp_text user "Author: Antmicro"
			(at -0.95 -4.169 180)
			(layer "B.Fab")
			(effects
				(font
					(size 0.7 0.7)
					(thickness 0.15)
				)
				(justify left bottom mirror)
			)
		)
		(pad "1" smd roundrect
			(at -0.48 0)
			(size 0.59 0.64)
			(layers "B.Cu" "B.Mask" "B.Paste")
			(roundrect_rratio 0.25)
			(net 368 "/I^{2}C + I3C/I3C_EXT.SDA")
			(pintype "passive")
		)
		(pad "2" smd roundrect
			(at 0.48 0)
			(size 0.59 0.64)
			(layers "B.Cu" "B.Mask" "B.Paste")
			(roundrect_rratio 0.25)
			(net 782 "Net-(Q24-D)")
			(pintype "passive")
		)
	)
)
